# BASEBOARD_FAB2 (Tioga Pass) — schematic netlist excerpt (pin names and nets, part order shuffled) for the footprints in the layout excerpt that follows; sources: Cadence DE-HDL packaged netlist, KiCad conversion of Wiwynn_Tioga_Pass_MB.brd

C3N11  CAP_A  22.0UF 4V 20% X6S  pkg 0603V  page 132 : A = PVNN_PCH_STBY ; B = GND
C2L51  CAP_A  0.01UF 25V 10% X7R  pkg 0402V  page 172 : A = SATA6G_S1_TX_C_DN ; B = SATA6G_S1_TX_DN

(kicad_pcb
	(version 20260206)
	(generator "pcbnew")
	(generator_version "10.0")
	(general
		(thickness 1.6)
		(legacy_teardrops no)
	)
	(paper "A4")
	(title_block
		(title "Wiwynn_Tioga_Pass_MB.brd")
		(comment 1 "Tioga Pass / footprints 3139-3140 of 4770")
	)
	(layers
		(0 "F.Cu" signal "TOP")
		(4 "In1.Cu" signal "L2GND")
		(6 "In2.Cu" signal "L3")
		(8 "In3.Cu" signal "L4GND")
		(10 "In4.Cu" signal "L5")
		(12 "In5.Cu" signal "L6GND")
		(14 "In6.Cu" signal "L7VCC")
		(16 "In7.Cu" signal "L8VCC")
		(18 "In8.Cu" signal "L9GND")
		(20 "In9.Cu" signal "L10")
		(22 "In10.Cu" signal "L11GND")
		(24 "In11.Cu" signal "L12")
		(26 "In12.Cu" signal "L13GND")
		(2 "B.Cu" signal "BOTTOM")
		(9 "F.Adhes" user "F.Adhesive")
		(11 "B.Adhes" user "B.Adhesive")
		(13 "F.Paste" user "Package Geometry/Pastemask Top")
		(15 "B.Paste" user "Package Geometry/Pastemask Bottom")
		(5 "F.SilkS" user "Ref Des/Silkscreen Top")
		(7 "B.SilkS" user "Ref Des/Silkscreen Bottom")
		(1 "F.Mask" user "Board Geometry/Soldermask Top")
		(3 "B.Mask" user "Board Geometry/Soldermask Bottom")
		(17 "Dwgs.User" user "User.Drawings")
		(19 "Cmts.User" user "User.Comments")
		(21 "Eco1.User" user "User.Eco1")
		(23 "Eco2.User" user "User.Eco2")
		(25 "Edge.Cuts" user "Board Geometry/Outline")
		(27 "Margin" user)
		(31 "F.CrtYd" user "Package Geometry/Place Bound Top")
		(29 "B.CrtYd" user "Package Geometry/Place Bound Bottom")
		(35 "F.Fab" user "Ref Des/Assembly Top")
		(33 "B.Fab" user "Ref Des/Assembly Bottom")
	)
	(footprint ""
		(layer "B.Cu")
		(at 430.85512 -141.101318 90)
		(property "Reference" "C2L51"
			(at 0 0 90)
			(layer "B.SilkS")
			(hide yes)
			(effects
				(font
					(size 1.27 1.27)
				)
				(justify mirror)
			)
		)
		(property "Value" ""
			(at 0 0 90)
			(layer "B.Fab")
			(effects
				(font
					(size 1.27 1.27)
				)
				(justify mirror)
			)
		)
		(duplicate_pad_numbers_are_jumpers no)
		(fp_poly
			(pts
				(xy -0.3048 -0.1016) (xy -0.3048 0.9906) (xy 0.3048 0.9906) (xy 0.3048 -0.1016)
			)
			(stroke
				(width 0)
				(type default)
			)
			(fill no)
			(layer "B.CrtYd")
		)
		(fp_line
			(start 0.3048 -0.1016)
			(end 0.3048 0.9906)
			(stroke
				(width 0.1)
				(type default)
			)
			(layer "B.Fab")
		)
		(fp_line
			(start -0.3048 -0.1016)
			(end 0.3048 -0.1016)
			(stroke
				(width 0.1)
				(type default)
			)
			(layer "B.Fab")
		)
		(fp_line
			(start 0.3048 0.9906)
			(end -0.3048 0.9906)
			(stroke
				(width 0.1)
				(type default)
			)
			(layer "B.Fab")
		)
		(fp_line
			(start -0.3048 0.9906)
			(end -0.3048 -0.1016)
			(stroke
				(width 0.1)
				(type default)
			)
			(layer "B.Fab")
		)
		(pad "1" smd rect
			(at 0 0 270)
			(size 0.508 0.508)
			(layers "B.Cu" "B.Mask" "B.Paste")
			(net "SATA6G_S1_TX_C_DN")
		)
		(pad "2" smd rect
			(at 0 0.889 270)
			(size 0.508 0.508)
			(layers "B.Cu" "B.Mask" "B.Paste")
			(net "SATA6G_S1_TX_DN")
		)
		(zone
			(layer "B.Cu")
			(hatch none 0.5)
			(connect_pads
				(clearance 0)
			)
			(min_thickness 0.25)
			(keepout
				(tracks allowed)
				(vias not_allowed)
				(pads allowed)
				(copperpour not_allowed)
				(footprints allowed)
			)
			(placement
				(enabled no)
				(sheetname "")
			)
			(fill
				(thermal_gap 0.5)
				(thermal_bridge_width 0.5)
				(island_removal_mode 0)
			)
			(polygon
				(pts
					(xy 431.10912 -141.355318) (xy 431.10912 -140.847318) (xy 431.49012 -140.847318) (xy 431.49012 -141.355318)
				)
			)
		)
		(zone
			(layer "B.Cu")
			(hatch none 0.5)
			(connect_pads
				(clearance 0)
			)
			(min_thickness 0.25)
			(keepout
				(tracks not_allowed)
				(vias allowed)
				(pads allowed)
				(copperpour not_allowed)
				(footprints allowed)
			)
			(placement
				(enabled no)
				(sheetname "")
			)
			(fill
				(thermal_gap 0.5)
				(thermal_bridge_width 0.5)
				(island_removal_mode 0)
			)
			(polygon
				(pts
					(xy 431.49012 -141.355318) (xy 431.49012 -140.847318) (xy 431.10912 -140.847318) (xy 431.10912 -141.355318)
				)
			)
		)
	)
	(footprint ""
		(layer "B.Cu")
		(at 384.4036 -109.855 -90)
		(property "Reference" "C3N11"
			(at 0 0 90)
			(layer "B.SilkS")
			(hide yes)
			(effects
				(font
					(size 1.27 1.27)
				)
				(justify mirror)
			)
		)
		(property "Value" ""
			(at 0 0 90)
			(layer "B.Fab")
			(effects
				(font
					(size 1.27 1.27)
				)
				(justify mirror)
			)
		)
		(duplicate_pad_numbers_are_jumpers no)
		(fp_rect
			(start 0.499872 1.522476)
			(end -0.500126 -0.277622)
			(stroke
				(width 0)
				(type default)
			)
			(fill no)
			(layer "B.CrtYd")
		)
		(fp_line
			(start -0.500126 1.522476)
			(end 0.499872 1.522476)
			(stroke
				(width 0.1)
				(type default)
			)
			(layer "B.Fab")
		)
		(fp_line
			(start 0.499872 1.522476)
			(end 0.499872 -0.277622)
			(stroke
				(width 0.1)
				(type default)
			)
			(layer "B.Fab")
		)
		(fp_line
			(start -0.500126 -0.277622)
			(end -0.500126 1.522476)
			(stroke
				(width 0.1)
				(type default)
			)
			(layer "B.Fab")
		)
		(fp_line
			(start 0.499872 -0.277622)
			(end -0.500126 -0.277622)
			(stroke
				(width 0.1)
				(type default)
			)
			(layer "B.Fab")
		)
		(pad "1" smd custom
			(at 0 0 180)
			(size 0.18415 0.18415)
			(layers "B.Cu" "B.Mask" "B.Paste")
			(net "PVNN_PCH_STBY")
			(options
				(clearance outline)
				(anchor circle)
			)
			(primitives
				(gr_poly
					(pts
						(arc
							(start -0.3683 0.2794)
							(mid -0.338542 0.351242)
							(end -0.2667 0.381)
						)
						(arc
							(start 0.2667 0.381)
							(mid 0.338542 0.351242)
							(end 0.3683 0.2794)
						)
						(arc
							(start 0.3683 -0.2794)
							(mid 0.338542 -0.351242)
							(end 0.2667 -0.381)
						)
						(arc
							(start -0.2667 -0.381)
							(mid -0.338542 -0.351242)
							(end -0.3683 -0.2794)
						)
					)
					(width 0)
					(fill yes)
				)
			)
		)
		(pad "2" smd custom
			(at 0 1.2446 180)
			(size 0.18415 0.18415)
			(layers "B.Cu" "B.Mask" "B.Paste")
			(net "GND")
			(options
				(clearance outline)
				(anchor circle)
			)
			(primitives
				(gr_poly
					(pts
						(arc
							(start -0.3683 0.2794)
							(mid -0.338542 0.351242)
							(end -0.2667 0.381)
						)
						(arc
							(start 0.2667 0.381)
							(mid 0.338542 0.351242)
							(end 0.3683 0.2794)
						)
						(arc
							(start 0.3683 -0.2794)
							(mid 0.338542 -0.351242)
							(end 0.2667 -0.381)
						)
						(arc
							(start -0.2667 -0.381)
							(mid -0.338542 -0.351242)
							(end -0.3683 -0.2794)
						)
					)
					(width 0)
					(fill yes)
				)
			)
		)
		(zone
			(layer "B.Cu")
			(hatch none 0.5)
			(connect_pads
				(clearance 0)
			)
			(min_thickness 0.25)
			(keepout
				(tracks allowed)
				(vias not_allowed)
				(pads allowed)
				(copperpour not_allowed)
				(footprints allowed)
			)
			(placement
				(enabled no)
				(sheetname "")
			)
			(fill
				(thermal_gap 0.5)
				(thermal_bridge_width 0.5)
				(island_removal_mode 0)
			)
			(polygon
				(pts
					(xy 383.5273 -109.474) (xy 384.0353 -109.474) (xy 384.0353 -110.236) (xy 383.5273 -110.236)
				)
			)
		)
		(zone
			(layer "B.Cu")
			(hatch none 0.5)
			(connect_pads
				(clearance 0)
			)
			(min_thickness 0.25)
			(keepout
				(tracks not_allowed)
				(vias allowed)
				(pads allowed)
				(copperpour not_allowed)
				(footprints allowed)
			)
			(placement
				(enabled no)
				(sheetname "")
			)
			(fill
				(thermal_gap 0.5)
				(thermal_bridge_width 0.5)
				(island_removal_mode 0)
			)
			(polygon
				(pts
					(xy 383.5273 -109.474) (xy 384.0353 -109.474) (xy 384.0353 -110.236) (xy 383.5273 -110.236)
				)
			)
		)
	)
)
